FILE_TYPE = MACRO_DRAWING;
SET COLOR_WIRE YELLOW;
SET COLOR_PROP MONO;
SET COLOR_DOT WHITE;
SET COLOR_ARC YELLOW;
SET COLOR_BODY GREEN;
SET COLOR_NOTE MONO;
SET PROP_DISPLAY VALUE;
SET PAGE_NUMBER P73;
FORCEADD VCC_CORE..1
(-1800 4100);
FORCEPROP 3 LASTPIN (-1800 4050) SIG_NAME PVCCMCP_CPU1\g
J 0
(-1790 4060);
DISPLAY 0.659574 (-1790 4060);
PAINT MONO (-1790 4060);
DISPLAY INVISIBLE (-1790 4060);
FORCEPROP 1 LAST HDL_POWER PVCCMCP_CPU1
J 1
(-1800 4150);
DISPLAY 0.617021 (-1800 4150);
PAINT GREEN (-1800 4150);
FORCEPROP 1 LAST PATH I104
J 0
(-1750 4125);
DISPLAY 0.872340 (-1750 4125);
PAINT AQUA (-1750 4125);
DISPLAY INVISIBLE (-1750 4125);
FORCEPROP 2 LAST CDS_LIB mstr_symbols
J 0
(-1800 4100);
PAINT ORANGE (-1800 4100);
DISPLAY INVISIBLE (-1800 4100);
FORCEADD VCC_CORE..1
(-6600 1975);
FORCEPROP 3 LASTPIN (-6600 1925) SIG_NAME PVCCMCP_CPU1\g
J 0
(-6590 1935);
DISPLAY 0.659574 (-6590 1935);
PAINT MONO (-6590 1935);
DISPLAY INVISIBLE (-6590 1935);
FORCEPROP 1 LAST HDL_POWER PVCCMCP_CPU1
J 1
(-6600 2025);
DISPLAY 0.617021 (-6600 2025);
PAINT GREEN (-6600 2025);
FORCEPROP 1 LAST PATH I105
J 0
(-6550 2000);
DISPLAY 0.872340 (-6550 2000);
PAINT AQUA (-6550 2000);
DISPLAY INVISIBLE (-6550 2000);
FORCEPROP 2 LAST CDS_LIB mstr_symbols
J 0
(-6600 1975);
PAINT ORANGE (-6600 1975);
DISPLAY INVISIBLE (-6600 1975);
FORCEADD SKX_EXT_B..22
(-4000 2550);
FORCEPROP 2 LASTPIN (-5050 2300) $PN BL16
J 2
(-5060 2310);
DISPLAY 0.617021 (-5060 2310);
PAINT ORANGE (-5060 2310);
FORCEPROP 2 LASTPIN (-5050 2600) $PN CN24
J 2
(-5060 2610);
DISPLAY 0.617021 (-5060 2610);
PAINT ORANGE (-5060 2610);
FORCEPROP 2 LASTPIN (-2950 2700) $PN DL38
J 0
(-2940 2710);
DISPLAY 0.617021 (-2940 2710);
PAINT ORANGE (-2940 2710);
FORCEPROP 2 LASTPIN (-5050 2350) $PN BN16
J 2
(-5060 2360);
DISPLAY 0.617021 (-5060 2360);
PAINT ORANGE (-5060 2360);
FORCEPROP 2 LASTPIN (-5050 2150) $PN BU16
J 2
(-5060 2160);
DISPLAY 0.617021 (-5060 2160);
PAINT ORANGE (-5060 2160);
FORCEPROP 2 LASTPIN (-5050 2200) $PN BT17
J 2
(-5060 2210);
DISPLAY 0.617021 (-5060 2210);
PAINT ORANGE (-5060 2210);
FORCEPROP 2 LASTPIN (-2950 950) $PN EF83
J 0
(-2940 960);
DISPLAY 0.617021 (-2940 960);
PAINT ORANGE (-2940 960);
FORCEPROP 2 LASTPIN (-2950 1000) $PN EF81
J 0
(-2940 1010);
DISPLAY 0.617021 (-2940 1010);
PAINT ORANGE (-2940 1010);
FORCEPROP 2 LASTPIN (-2950 1050) $PN EF77
J 0
(-2940 1060);
DISPLAY 0.617021 (-2940 1060);
PAINT ORANGE (-2940 1060);
FORCEPROP 2 LASTPIN (-2950 1100) $PN EF47
J 0
(-2940 1110);
DISPLAY 0.617021 (-2940 1110);
PAINT ORANGE (-2940 1110);
FORCEPROP 2 LASTPIN (-2950 1150) $PN EE84
J 0
(-2940 1160);
DISPLAY 0.617021 (-2940 1160);
PAINT ORANGE (-2940 1160);
FORCEPROP 2 LASTPIN (-2950 1200) $PN EE82
J 0
(-2940 1210);
DISPLAY 0.617021 (-2940 1210);
PAINT ORANGE (-2940 1210);
FORCEPROP 2 LASTPIN (-2950 1250) $PN EE6
J 0
(-2940 1260);
DISPLAY 0.617021 (-2940 1260);
PAINT ORANGE (-2940 1260);
FORCEPROP 2 LASTPIN (-2950 1300) $PN EE46
J 0
(-2940 1310);
DISPLAY 0.617021 (-2940 1310);
PAINT ORANGE (-2940 1310);
FORCEPROP 2 LASTPIN (-2950 1350) $PN EE16
J 0
(-2940 1360);
DISPLAY 0.617021 (-2940 1360);
PAINT ORANGE (-2940 1360);
FORCEPROP 2 LASTPIN (-2950 1400) $PN ED83
J 0
(-2940 1410);
DISPLAY 0.617021 (-2940 1410);
PAINT ORANGE (-2940 1410);
FORCEPROP 2 LASTPIN (-2950 1450) $PN ED5
J 0
(-2940 1460);
DISPLAY 0.617021 (-2940 1460);
PAINT ORANGE (-2940 1460);
FORCEPROP 2 LASTPIN (-2950 1500) $PN ED45
J 0
(-2940 1510);
DISPLAY 0.617021 (-2940 1510);
PAINT ORANGE (-2940 1510);
FORCEPROP 2 LASTPIN (-2950 1550) $PN EC84
J 0
(-2940 1560);
DISPLAY 0.617021 (-2940 1560);
PAINT ORANGE (-2940 1560);
FORCEPROP 2 LASTPIN (-2950 1600) $PN EC44
J 0
(-2940 1610);
DISPLAY 0.617021 (-2940 1610);
PAINT ORANGE (-2940 1610);
FORCEPROP 2 LASTPIN (-2950 1650) $PN EC4
J 0
(-2940 1660);
DISPLAY 0.617021 (-2940 1660);
PAINT ORANGE (-2940 1660);
FORCEPROP 2 LASTPIN (-2950 1700) $PN EC16
J 0
(-2940 1710);
DISPLAY 0.617021 (-2940 1710);
PAINT ORANGE (-2940 1710);
FORCEPROP 2 LASTPIN (-2950 1750) $PN EB85
J 0
(-2940 1760);
DISPLAY 0.617021 (-2940 1760);
PAINT ORANGE (-2940 1760);
FORCEPROP 2 LASTPIN (-2950 1800) $PN EB5
J 0
(-2940 1810);
DISPLAY 0.617021 (-2940 1810);
PAINT ORANGE (-2940 1810);
FORCEPROP 2 LASTPIN (-2950 1850) $PN EB3
J 0
(-2940 1860);
DISPLAY 0.617021 (-2940 1860);
PAINT ORANGE (-2940 1860);
FORCEPROP 2 LASTPIN (-2950 1900) $PN EA44
J 0
(-2940 1910);
DISPLAY 0.617021 (-2940 1910);
PAINT ORANGE (-2940 1910);
FORCEPROP 2 LASTPIN (-2950 1950) $PN EA4
J 0
(-2940 1960);
DISPLAY 0.617021 (-2940 1960);
PAINT ORANGE (-2940 1960);
FORCEPROP 2 LASTPIN (-2950 2000) $PN DY3
J 0
(-2940 2010);
DISPLAY 0.617021 (-2940 2010);
PAINT ORANGE (-2940 2010);
FORCEPROP 2 LASTPIN (-2950 2050) $PN DW46
J 0
(-2940 2060);
DISPLAY 0.617021 (-2940 2060);
PAINT ORANGE (-2940 2060);
FORCEPROP 2 LASTPIN (-2950 2100) $PN DW44
J 0
(-2940 2110);
DISPLAY 0.617021 (-2940 2110);
PAINT ORANGE (-2940 2110);
FORCEPROP 2 LASTPIN (-2950 2150) $PN DV71
J 0
(-2940 2160);
DISPLAY 0.617021 (-2940 2160);
PAINT ORANGE (-2940 2160);
FORCEPROP 2 LASTPIN (-2950 2200) $PN DV61
J 0
(-2940 2210);
DISPLAY 0.617021 (-2940 2210);
PAINT ORANGE (-2940 2210);
FORCEPROP 2 LASTPIN (-2950 2250) $PN DU44
J 0
(-2940 2260);
DISPLAY 0.617021 (-2940 2260);
PAINT ORANGE (-2940 2260);
FORCEPROP 2 LASTPIN (-2950 2300) $PN DT71
J 0
(-2940 2310);
DISPLAY 0.617021 (-2940 2310);
PAINT ORANGE (-2940 2310);
FORCEPROP 2 LASTPIN (-2950 2350) $PN DR44
J 0
(-2940 2360);
DISPLAY 0.617021 (-2940 2360);
PAINT ORANGE (-2940 2360);
FORCEPROP 2 LASTPIN (-2950 2400) $PN DP65
J 0
(-2940 2410);
DISPLAY 0.617021 (-2940 2410);
PAINT ORANGE (-2940 2410);
FORCEPROP 2 LASTPIN (-2950 2450) $PN DP17
J 0
(-2940 2460);
DISPLAY 0.617021 (-2940 2460);
PAINT ORANGE (-2940 2460);
FORCEPROP 2 LASTPIN (-2950 2500) $PN DN66
J 0
(-2940 2510);
DISPLAY 0.617021 (-2940 2510);
PAINT ORANGE (-2940 2510);
FORCEPROP 2 LASTPIN (-2950 2550) $PN DN62
J 0
(-2940 2560);
DISPLAY 0.617021 (-2940 2560);
PAINT ORANGE (-2940 2560);
FORCEPROP 2 LASTPIN (-2950 2600) $PN DM67
J 0
(-2940 2610);
DISPLAY 0.617021 (-2940 2610);
PAINT ORANGE (-2940 2610);
FORCEPROP 2 LASTPIN (-2950 2650) $PN DL66
J 0
(-2940 2660);
DISPLAY 0.617021 (-2940 2660);
PAINT ORANGE (-2940 2660);
FORCEPROP 2 LASTPIN (-2950 2750) $PN DK67
J 0
(-2940 2760);
DISPLAY 0.617021 (-2940 2760);
PAINT ORANGE (-2940 2760);
FORCEPROP 2 LASTPIN (-2950 2800) $PN DK65
J 0
(-2940 2810);
DISPLAY 0.617021 (-2940 2810);
PAINT ORANGE (-2940 2810);
FORCEPROP 2 LASTPIN (-2950 2850) $PN DK37
J 0
(-2940 2860);
DISPLAY 0.617021 (-2940 2860);
PAINT ORANGE (-2940 2860);
FORCEPROP 2 LASTPIN (-2950 2900) $PN DK15
J 0
(-2940 2910);
DISPLAY 0.617021 (-2940 2910);
PAINT ORANGE (-2940 2910);
FORCEPROP 2 LASTPIN (-2950 2950) $PN DJ66
J 0
(-2940 2960);
DISPLAY 0.617021 (-2940 2960);
PAINT ORANGE (-2940 2960);
FORCEPROP 2 LASTPIN (-2950 3000) $PN DJ36
J 0
(-2940 3010);
DISPLAY 0.617021 (-2940 3010);
PAINT ORANGE (-2940 3010);
FORCEPROP 2 LASTPIN (-2950 3050) $PN DH65
J 0
(-2940 3060);
DISPLAY 0.617021 (-2940 3060);
PAINT ORANGE (-2940 3060);
FORCEPROP 2 LASTPIN (-2950 3100) $PN DG64
J 0
(-2940 3110);
DISPLAY 0.617021 (-2940 3110);
PAINT ORANGE (-2940 3110);
FORCEPROP 2 LASTPIN (-2950 3150) $PN DG36
J 0
(-2940 3160);
DISPLAY 0.617021 (-2940 3160);
PAINT ORANGE (-2940 3160);
FORCEPROP 2 LASTPIN (-2950 3250) $PN DC52
J 0
(-2940 3260);
DISPLAY 0.617021 (-2940 3260);
PAINT ORANGE (-2940 3260);
FORCEPROP 2 LASTPIN (-2950 3300) $PN DC46
J 0
(-2940 3310);
DISPLAY 0.617021 (-2940 3310);
PAINT ORANGE (-2940 3310);
FORCEPROP 2 LASTPIN (-2950 3350) $PN DA56
J 0
(-2940 3360);
DISPLAY 0.617021 (-2940 3360);
PAINT ORANGE (-2940 3360);
FORCEPROP 2 LASTPIN (-2950 3400) $PN DA54
J 0
(-2940 3410);
DISPLAY 0.617021 (-2940 3410);
PAINT ORANGE (-2940 3410);
FORCEPROP 2 LASTPIN (-2950 3450) $PN DA52
J 0
(-2940 3460);
DISPLAY 0.617021 (-2940 3460);
PAINT ORANGE (-2940 3460);
FORCEPROP 2 LASTPIN (-2950 3500) $PN DA40
J 0
(-2940 3510);
DISPLAY 0.617021 (-2940 3510);
PAINT ORANGE (-2940 3510);
FORCEPROP 2 LASTPIN (-2950 3550) $PN DA24
J 0
(-2940 3560);
DISPLAY 0.617021 (-2940 3560);
PAINT ORANGE (-2940 3560);
FORCEPROP 2 LASTPIN (-2950 3600) $PN CY73
J 0
(-2940 3610);
DISPLAY 0.617021 (-2940 3610);
PAINT ORANGE (-2940 3610);
FORCEPROP 2 LASTPIN (-2950 3650) $PN CY63
J 0
(-2940 3660);
DISPLAY 0.617021 (-2940 3660);
PAINT ORANGE (-2940 3660);
FORCEPROP 2 LASTPIN (-2950 3700) $PN CY57
J 0
(-2940 3710);
DISPLAY 0.617021 (-2940 3710);
PAINT ORANGE (-2940 3710);
FORCEPROP 2 LASTPIN (-2950 3750) $PN CY53
J 0
(-2940 3760);
DISPLAY 0.617021 (-2940 3760);
PAINT ORANGE (-2940 3760);
FORCEPROP 2 LASTPIN (-2950 3800) $PN CY39
J 0
(-2940 3810);
DISPLAY 0.617021 (-2940 3810);
PAINT ORANGE (-2940 3810);
FORCEPROP 2 LASTPIN (-2950 3850) $PN CY25
J 0
(-2940 3860);
DISPLAY 0.617021 (-2940 3860);
PAINT ORANGE (-2940 3860);
FORCEPROP 2 LASTPIN (-2950 3900) $PN CY23
J 0
(-2940 3910);
DISPLAY 0.617021 (-2940 3910);
PAINT ORANGE (-2940 3910);
FORCEPROP 2 LASTPIN (-2950 3950) $PN CW62
J 0
(-2940 3960);
DISPLAY 0.617021 (-2940 3960);
PAINT ORANGE (-2940 3960);
FORCEPROP 2 LASTPIN (-5050 1200) $PN CW60
J 2
(-5060 1210);
DISPLAY 0.617021 (-5060 1210);
PAINT ORANGE (-5060 1210);
FORCEPROP 2 LASTPIN (-5050 1250) $PN CW24
J 2
(-5060 1260);
DISPLAY 0.617021 (-5060 1260);
PAINT ORANGE (-5060 1260);
FORCEPROP 2 LASTPIN (-5050 1300) $PN CW22
J 2
(-5060 1310);
DISPLAY 0.617021 (-5060 1310);
PAINT ORANGE (-5060 1310);
FORCEPROP 2 LASTPIN (-5050 1350) $PN CV69
J 2
(-5060 1360);
DISPLAY 0.617021 (-5060 1360);
PAINT ORANGE (-5060 1360);
FORCEPROP 2 LASTPIN (-5050 1400) $PN CV23
J 2
(-5060 1410);
DISPLAY 0.617021 (-5060 1410);
PAINT ORANGE (-5060 1410);
FORCEPROP 2 LASTPIN (-5050 1450) $PN CU60
J 2
(-5060 1460);
DISPLAY 0.617021 (-5060 1460);
PAINT ORANGE (-5060 1460);
FORCEPROP 2 LASTPIN (-5050 1500) $PN CU6
J 2
(-5060 1510);
DISPLAY 0.617021 (-5060 1510);
PAINT ORANGE (-5060 1510);
FORCEPROP 2 LASTPIN (-5050 1550) $PN CU24
J 2
(-5060 1560);
DISPLAY 0.617021 (-5060 1560);
PAINT ORANGE (-5060 1560);
FORCEPROP 2 LASTPIN (-5050 1600) $PN CT69
J 2
(-5060 1610);
DISPLAY 0.617021 (-5060 1610);
PAINT ORANGE (-5060 1610);
FORCEPROP 2 LASTPIN (-5050 1650) $PN CT5
J 2
(-5060 1660);
DISPLAY 0.617021 (-5060 1660);
PAINT ORANGE (-5060 1660);
FORCEPROP 2 LASTPIN (-5050 1700) $PN CT23
J 2
(-5060 1710);
DISPLAY 0.617021 (-5060 1710);
PAINT ORANGE (-5060 1710);
FORCEPROP 2 LASTPIN (-5050 1750) $PN CR60
J 2
(-5060 1760);
DISPLAY 0.617021 (-5060 1760);
PAINT ORANGE (-5060 1760);
FORCEPROP 2 LASTPIN (-5050 1800) $PN CP31
J 2
(-5060 1810);
DISPLAY 0.617021 (-5060 1810);
PAINT ORANGE (-5060 1810);
FORCEPROP 2 LASTPIN (-5050 1850) $PN CP23
J 2
(-5060 1860);
DISPLAY 0.617021 (-5060 1860);
PAINT ORANGE (-5060 1860);
FORCEPROP 2 LASTPIN (-5050 1900) $PN CN28
J 2
(-5060 1910);
DISPLAY 0.617021 (-5060 1910);
PAINT ORANGE (-5060 1910);
FORCEPROP 2 LASTPIN (-5050 2650) $PN CN22
J 2
(-5060 2660);
DISPLAY 0.617021 (-5060 2660);
PAINT ORANGE (-5060 2660);
FORCEPROP 2 LASTPIN (-5050 2700) $PN CM25
J 2
(-5060 2710);
DISPLAY 0.617021 (-5060 2710);
PAINT ORANGE (-5060 2710);
FORCEPROP 2 LASTPIN (-5050 2800) $PN CL26
J 2
(-5060 2810);
DISPLAY 0.617021 (-5060 2810);
PAINT ORANGE (-5060 2810);
FORCEPROP 2 LASTPIN (-5050 3000) $PN AF5
J 2
(-5060 3010);
DISPLAY 0.617021 (-5060 3010);
PAINT ORANGE (-5060 3010);
FORCEPROP 2 LASTPIN (-5050 3100) $PN AM5
J 2
(-5060 3110);
DISPLAY 0.617021 (-5060 3110);
PAINT ORANGE (-5060 3110);
FORCEPROP 2 LASTPIN (-5050 3150) $PN AT5
J 2
(-5060 3160);
DISPLAY 0.617021 (-5060 3160);
PAINT ORANGE (-5060 3160);
FORCEPROP 2 LASTPIN (-5050 3200) $PN AT7
J 2
(-5060 3210);
DISPLAY 0.617021 (-5060 3210);
PAINT ORANGE (-5060 3210);
FORCEPROP 2 LASTPIN (-5050 3250) $PN BE24
J 2
(-5060 3260);
DISPLAY 0.617021 (-5060 3260);
PAINT ORANGE (-5060 3260);
FORCEPROP 2 LASTPIN (-5050 3300) $PN DK21
J 2
(-5060 3310);
DISPLAY 0.617021 (-5060 3310);
PAINT ORANGE (-5060 3310);
FORCEPROP 2 LASTPIN (-5050 3350) $PN CF5
J 2
(-5060 3360);
DISPLAY 0.617021 (-5060 3360);
PAINT ORANGE (-5060 3360);
FORCEPROP 2 LASTPIN (-5050 3450) $PN CG14
J 2
(-5060 3460);
DISPLAY 0.617021 (-5060 3460);
PAINT ORANGE (-5060 3460);
FORCEPROP 2 LASTPIN (-5050 3500) $PN CL20
J 2
(-5060 3510);
DISPLAY 0.617021 (-5060 3510);
PAINT ORANGE (-5060 3510);
FORCEPROP 2 LASTPIN (-5050 3550) $PN CP13
J 2
(-5060 3560);
DISPLAY 0.617021 (-5060 3560);
PAINT ORANGE (-5060 3560);
FORCEPROP 2 LASTPIN (-5050 3600) $PN DE14
J 2
(-5060 3610);
DISPLAY 0.617021 (-5060 3610);
PAINT ORANGE (-5060 3610);
FORCEPROP 2 LASTPIN (-5050 3650) $PN DC18
J 2
(-5060 3660);
DISPLAY 0.617021 (-5060 3660);
PAINT ORANGE (-5060 3660);
FORCEPROP 2 LASTPIN (-5050 3700) $PN CY17
J 2
(-5060 3710);
DISPLAY 0.617021 (-5060 3710);
PAINT ORANGE (-5060 3710);
FORCEPROP 2 LASTPIN (-5050 3750) $PN CU18
J 2
(-5060 3760);
DISPLAY 0.617021 (-5060 3760);
PAINT ORANGE (-5060 3760);
FORCEPROP 2 LASTPIN (-5050 3800) $PN CV21
J 2
(-5060 3810);
DISPLAY 0.617021 (-5060 3810);
PAINT ORANGE (-5060 3810);
FORCEPROP 2 LASTPIN (-5050 3900) $PN CU12
J 2
(-5060 3910);
DISPLAY 0.617021 (-5060 3910);
PAINT ORANGE (-5060 3910);
FORCEPROP 2 LASTPIN (-5050 3950) $PN CN6
J 2
(-5060 3960);
DISPLAY 0.617021 (-5060 3960);
PAINT ORANGE (-5060 3960);
FORCEPROP 2 LASTPIN (-5050 2050) $PN BH5
J 2
(-5060 2060);
DISPLAY 0.617021 (-5060 2060);
PAINT ORANGE (-5060 2060);
FORCEPROP 2 LASTPIN (-5050 2500) $PN CE76
J 2
(-5060 2510);
DISPLAY 0.617021 (-5060 2510);
PAINT ORANGE (-5060 2510);
FORCEPROP 2 LASTPIN (-5050 2000) $PN BF5
J 2
(-5060 2010);
DISPLAY 0.617021 (-5060 2010);
PAINT ORANGE (-5060 2010);
FORCEPROP 2 LASTPIN (-5050 2450) $PN CG76
J 2
(-5060 2460);
DISPLAY 0.617021 (-5060 2460);
PAINT ORANGE (-5060 2460);
FORCEPROP 1 LAST MATERIAL IC
J 0
(-5000 4150);
DISPLAY 0.617021 (-5000 4150);
PAINT SKYBLUE (-5000 4150);
FORCEPROP 1 LAST PART_NUMBER TBD
J 0
(-5000 750);
DISPLAY 0.617021 (-5000 750);
PAINT BLUE (-5000 750);
FORCEPROP 1 LAST LOCATION U2D1
J 0
(-5000 4200);
DISPLAY 0.617021 (-5000 4200);
PAINT AQUA (-5000 4200);
FORCEPROP 2 LASTPIN (-5050 3050) $PN DV11
J 2
(-5060 3060);
DISPLAY 0.617021 (-5060 3060);
PAINT ORANGE (-5060 3060);
FORCEPROP 2 LASTPIN (-5050 2750) $PN CM23
J 2
(-5060 2760);
DISPLAY 0.617021 (-5060 2760);
PAINT ORANGE (-5060 2760);
FORCEPROP 2 LASTPIN (-5050 2950) $PN AE10
J 2
(-5060 2960);
DISPLAY 0.617021 (-5060 2960);
PAINT ORANGE (-5060 2960);
FORCEPROP 2 LASTPIN (-5050 2900) $PN EE10
J 2
(-5060 2910);
DISPLAY 0.617021 (-5060 2910);
PAINT ORANGE (-5060 2910);
FORCEPROP 2 LASTPIN (-2950 3200) $PN DD51
J 0
(-2940 3210);
DISPLAY 0.617021 (-2940 3210);
PAINT ORANGE (-2940 3210);
FORCEPROP 1 LAST PATH I107
J 0
(-4000 4150);
PAINT GREEN (-4000 4150);
DISPLAY INVISIBLE (-4000 4150);
FORCEPROP 2 LAST CDS_LOCATION U2D1
J 0
(-5000 4200);
DISPLAY 0.617021 (-5000 4200);
PAINT AQUA (-5000 4200);
DISPLAY INVISIBLE (-5000 4200);
FORCEPROP 2 LAST SEC 22
J 0
(-5000 4250);
DISPLAY 0.680851 (-5000 4250);
PAINT MONO (-5000 4250);
DISPLAY INVISIBLE (-5000 4250);
FORCEPROP 2 LAST CDS_LIB chpset_lib
J 0
(-4000 2550);
PAINT ORANGE (-4000 2550);
DISPLAY INVISIBLE (-4000 2550);
FORCEPROP 2 LAST SEC_TYPE BGA1
J 0
(-5000 4250);
DISPLAY 1.021277 (-5000 4250);
PAINT ORANGE (-5000 4250);
DISPLAY INVISIBLE (-5000 4250);
FORCEPROP 1 LAST PACK_TYPE BGA1
J 0
(-5000 4250);
PAINT SKYBLUE (-5000 4250);
DISPLAY INVISIBLE (-5000 4250);
FORCEADD VCC_CORE..1
(-5925 2950);
FORCEPROP 3 LASTPIN (-5925 2900) SIG_NAME PVCCMCP_CPU1\g
J 0
(-5915 2910);
DISPLAY 0.659574 (-5915 2910);
PAINT MONO (-5915 2910);
DISPLAY INVISIBLE (-5915 2910);
FORCEPROP 1 LAST HDL_POWER PVCCMCP_CPU1
J 1
(-5925 3000);
DISPLAY 0.617021 (-5925 3000);
PAINT GREEN (-5925 3000);
FORCEPROP 1 LAST PATH I108
J 0
(-5875 2975);
DISPLAY 0.872340 (-5875 2975);
PAINT AQUA (-5875 2975);
DISPLAY INVISIBLE (-5875 2975);
FORCEPROP 2 LAST CDS_LIB mstr_symbols
J 0
(-5925 2950);
PAINT ORANGE (-5925 2950);
DISPLAY INVISIBLE (-5925 2950);
FORCEADD OFFPAGE..1
(-6125 1900);
FORCEPROP 2 LAST $XR0 97 
J 0
(-6346 1900);
DISPLAY 0.638298 (-6346 1900);
PAINT MONO (-6346 1900);
FORCEPROP 2 LAST PATH I109
J 0
(-6075 1975);
DISPLAY 1.021277 (-6075 1975);
PAINT ORANGE (-6075 1975);
DISPLAY INVISIBLE (-6075 1975);
FORCEPROP 1 LAST COMMENT_BODY TRUE
J 0
(-6000 1800);
DISPLAY 0.872340 (-6000 1800);
PAINT GREEN (-6000 1800);
DISPLAY INVISIBLE (-6000 1800);
FORCEPROP 1 LAST OFFPAGE TRUE
J 0
(-5800 1775);
DISPLAY 0.872340 (-5800 1775);
PAINT GREEN (-5800 1775);
DISPLAY INVISIBLE (-5800 1775);
FORCEPROP 2 LAST CDS_LIB mstr_standard
J 0
(-6125 1900);
PAINT ORANGE (-6125 1900);
DISPLAY INVISIBLE (-6125 1900);
FORCEADD PVCCIO_CPU1..1
(-5350 4425);
FORCEPROP 3 LASTPIN (-5350 4375) SIG_NAME PVCCIO_CPU1\g
J 0
(-5340 4385);
DISPLAY 0.659574 (-5340 4385);
PAINT MONO (-5340 4385);
DISPLAY INVISIBLE (-5340 4385);
FORCEPROP 1 LAST HDL_POWER PVCCIO_CPU1
J 1
(-5350 4475);
DISPLAY 0.872340 (-5350 4475);
PAINT GREEN (-5350 4475);
DISPLAY INVISIBLE (-5350 4475);
FORCEPROP 1 LAST PATH I22
J 0
(-5300 4450);
DISPLAY 0.872340 (-5300 4450);
PAINT AQUA (-5300 4450);
DISPLAY INVISIBLE (-5300 4450);
FORCEPROP 1 LAST BODY_TYPE PLUMBING
J 0
(-5395 4382);
DISPLAY 0.340426 (-5395 4382);
PAINT GREEN (-5395 4382);
DISPLAY INVISIBLE (-5395 4382);
FORCEPROP 2 LAST CDS_LIB mstr_symbols
J 0
(-5350 4425);
PAINT ORANGE (-5350 4425);
DISPLAY INVISIBLE (-5350 4425);
FORCEPROP 1 LAST VOLTAGE 1.1V
J 0
(-5395 4382);
DISPLAY 0.340426 (-5395 4382);
PAINT SKYBLUE (-5395 4382);
DISPLAY INVISIBLE (-5395 4382);
FORCEADD OFFPAGE..5
(-6125 2500);
FORCEPROP 2 LAST $XR0 210 
J 0
(-6380 2500);
DISPLAY 0.638298 (-6380 2500);
PAINT MONO (-6380 2500);
FORCEPROP 2 LAST PATH I91
J 0
(-6375 2550);
DISPLAY 1.021277 (-6375 2550);
PAINT ORANGE (-6375 2550);
DISPLAY INVISIBLE (-6375 2550);
FORCEPROP 1 LAST COMMENT_BODY TRUE
J 0
(-6025 2425);
DISPLAY 0.680851 (-6025 2425);
PAINT PEACH (-6025 2425);
DISPLAY INVISIBLE (-6025 2425);
FORCEPROP 1 LAST OFFPAGE TRUE
J 0
(-5800 2375);
DISPLAY 0.680851 (-5800 2375);
PAINT GREEN (-5800 2375);
DISPLAY INVISIBLE (-5800 2375);
FORCEPROP 2 LAST CDS_LIB mstr_standard
J 0
(-6125 2500);
DISPLAY 0.489362 (-6125 2500);
PAINT ORANGE (-6125 2500);
DISPLAY INVISIBLE (-6125 2500);
FORCEADD OFFPAGE..5
(-6125 2450);
FORCEPROP 2 LAST $XR0 210 
J 0
(-6380 2450);
DISPLAY 0.638298 (-6380 2450);
PAINT MONO (-6380 2450);
FORCEPROP 2 LAST PATH I92
J 0
(-6375 2500);
DISPLAY 1.021277 (-6375 2500);
PAINT ORANGE (-6375 2500);
DISPLAY INVISIBLE (-6375 2500);
FORCEPROP 1 LAST COMMENT_BODY TRUE
J 0
(-6025 2375);
DISPLAY 0.680851 (-6025 2375);
PAINT PEACH (-6025 2375);
DISPLAY INVISIBLE (-6025 2375);
FORCEPROP 1 LAST OFFPAGE TRUE
J 0
(-5800 2325);
DISPLAY 0.680851 (-5800 2325);
PAINT GREEN (-5800 2325);
DISPLAY INVISIBLE (-5800 2325);
FORCEPROP 2 LAST CDS_LIB mstr_standard
J 0
(-6125 2450);
DISPLAY 0.489362 (-6125 2450);
PAINT ORANGE (-6125 2450);
DISPLAY INVISIBLE (-6125 2450);
FORCEADD OFFPAGE..5
(-6125 2350);
FORCEPROP 2 LAST $XR0 193 
J 0
(-6380 2350);
DISPLAY 0.638298 (-6380 2350);
PAINT MONO (-6380 2350);
FORCEPROP 2 LAST PATH I93
J 0
(-6375 2400);
DISPLAY 1.021277 (-6375 2400);
PAINT ORANGE (-6375 2400);
DISPLAY INVISIBLE (-6375 2400);
FORCEPROP 1 LAST COMMENT_BODY TRUE
J 0
(-6025 2275);
DISPLAY 0.680851 (-6025 2275);
PAINT PEACH (-6025 2275);
DISPLAY INVISIBLE (-6025 2275);
FORCEPROP 1 LAST OFFPAGE TRUE
J 0
(-5800 2225);
DISPLAY 0.680851 (-5800 2225);
PAINT GREEN (-5800 2225);
DISPLAY INVISIBLE (-5800 2225);
FORCEPROP 2 LAST CDS_LIB mstr_standard
J 0
(-6125 2350);
DISPLAY 0.489362 (-6125 2350);
PAINT ORANGE (-6125 2350);
DISPLAY INVISIBLE (-6125 2350);
FORCEADD OFFPAGE..5
(-6125 2300);
FORCEPROP 2 LAST $XR0 193 
J 0
(-6380 2300);
DISPLAY 0.638298 (-6380 2300);
PAINT MONO (-6380 2300);
FORCEPROP 2 LAST PATH I94
J 0
(-6375 2350);
DISPLAY 1.021277 (-6375 2350);
PAINT ORANGE (-6375 2350);
DISPLAY INVISIBLE (-6375 2350);
FORCEPROP 1 LAST COMMENT_BODY TRUE
J 0
(-6025 2225);
DISPLAY 0.680851 (-6025 2225);
PAINT PEACH (-6025 2225);
DISPLAY INVISIBLE (-6025 2225);
FORCEPROP 1 LAST OFFPAGE TRUE
J 0
(-5800 2175);
DISPLAY 0.680851 (-5800 2175);
PAINT GREEN (-5800 2175);
DISPLAY INVISIBLE (-5800 2175);
FORCEPROP 2 LAST CDS_LIB mstr_standard
J 0
(-6125 2300);
DISPLAY 0.489362 (-6125 2300);
PAINT ORANGE (-6125 2300);
DISPLAY INVISIBLE (-6125 2300);
FORCEADD OFFPAGE..5
(-6125 2200);
FORCEPROP 2 LAST $XR0 193 
J 0
(-6380 2200);
DISPLAY 0.638298 (-6380 2200);
PAINT MONO (-6380 2200);
FORCEPROP 2 LAST PATH I95
J 0
(-6375 2250);
DISPLAY 1.021277 (-6375 2250);
PAINT ORANGE (-6375 2250);
DISPLAY INVISIBLE (-6375 2250);
FORCEPROP 1 LAST COMMENT_BODY TRUE
J 0
(-6025 2125);
DISPLAY 0.680851 (-6025 2125);
PAINT PEACH (-6025 2125);
DISPLAY INVISIBLE (-6025 2125);
FORCEPROP 1 LAST OFFPAGE TRUE
J 0
(-5800 2075);
DISPLAY 0.680851 (-5800 2075);
PAINT GREEN (-5800 2075);
DISPLAY INVISIBLE (-5800 2075);
FORCEPROP 2 LAST CDS_LIB mstr_standard
J 0
(-6125 2200);
DISPLAY 0.489362 (-6125 2200);
PAINT ORANGE (-6125 2200);
DISPLAY INVISIBLE (-6125 2200);
FORCEADD OFFPAGE..5
(-6125 2150);
FORCEPROP 2 LAST $XR0 193 
J 0
(-6380 2150);
DISPLAY 0.638298 (-6380 2150);
PAINT MONO (-6380 2150);
FORCEPROP 2 LAST PATH I96
J 0
(-6375 2200);
DISPLAY 1.021277 (-6375 2200);
PAINT ORANGE (-6375 2200);
DISPLAY INVISIBLE (-6375 2200);
FORCEPROP 1 LAST COMMENT_BODY TRUE
J 0
(-6025 2075);
DISPLAY 0.680851 (-6025 2075);
PAINT PEACH (-6025 2075);
DISPLAY INVISIBLE (-6025 2075);
FORCEPROP 1 LAST OFFPAGE TRUE
J 0
(-5800 2025);
DISPLAY 0.680851 (-5800 2025);
PAINT GREEN (-5800 2025);
DISPLAY INVISIBLE (-5800 2025);
FORCEPROP 2 LAST CDS_LIB mstr_standard
J 0
(-6125 2150);
DISPLAY 0.489362 (-6125 2150);
PAINT ORANGE (-6125 2150);
DISPLAY INVISIBLE (-6125 2150);
FORCEADD OFFPAGE..5
(-6125 2000);
FORCEPROP 2 LAST $XR0 214 
J 0
(-6380 2000);
DISPLAY 0.638298 (-6380 2000);
PAINT MONO (-6380 2000);
FORCEPROP 2 LAST PATH I97
J 0
(-6375 2050);
DISPLAY 1.021277 (-6375 2050);
PAINT ORANGE (-6375 2050);
DISPLAY INVISIBLE (-6375 2050);
FORCEPROP 1 LAST COMMENT_BODY TRUE
J 0
(-6025 1925);
DISPLAY 0.680851 (-6025 1925);
PAINT PEACH (-6025 1925);
DISPLAY INVISIBLE (-6025 1925);
FORCEPROP 1 LAST OFFPAGE TRUE
J 0
(-5800 1875);
DISPLAY 0.680851 (-5800 1875);
PAINT GREEN (-5800 1875);
DISPLAY INVISIBLE (-5800 1875);
FORCEPROP 2 LAST CDS_LIB mstr_standard
J 0
(-6125 2000);
DISPLAY 0.489362 (-6125 2000);
PAINT ORANGE (-6125 2000);
DISPLAY INVISIBLE (-6125 2000);
FORCEADD OFFPAGE..5
(-6125 2050);
FORCEPROP 2 LAST $XR0 214 
J 0
(-6380 2050);
DISPLAY 0.638298 (-6380 2050);
PAINT MONO (-6380 2050);
FORCEPROP 2 LAST PATH I98
J 0
(-6375 2100);
DISPLAY 1.021277 (-6375 2100);
PAINT ORANGE (-6375 2100);
DISPLAY INVISIBLE (-6375 2100);
FORCEPROP 1 LAST COMMENT_BODY TRUE
J 0
(-6025 1975);
DISPLAY 0.680851 (-6025 1975);
PAINT PEACH (-6025 1975);
DISPLAY INVISIBLE (-6025 1975);
FORCEPROP 1 LAST OFFPAGE TRUE
J 0
(-5800 1925);
DISPLAY 0.680851 (-5800 1925);
PAINT GREEN (-5800 1925);
DISPLAY INVISIBLE (-5800 1925);
FORCEPROP 2 LAST CDS_LIB mstr_standard
J 0
(-6125 2050);
DISPLAY 0.489362 (-6125 2050);
PAINT ORANGE (-6125 2050);
DISPLAY INVISIBLE (-6125 2050);
FORCEADD PRELIM..10
(-3990 2615);
PAINT GRAY (-3990 2615);
FORCEPROP 1 LAST COMMENT_BODY TRUE
J 0
(-3990 2615);
PAINT ORANGE (-3990 2615);
DISPLAY INVISIBLE (-3990 2615);
FORCEPROP 2 LAST CDS_LIB mstr_misc
J 0
(-3990 2615);
PAINT ORANGE (-3990 2615);
DISPLAY INVISIBLE (-3990 2615);
FORCEADD INTEL_CORP_BPAGE..1
(0 0);
FORCEPROP 1 LAST CDS_CON_LAST_MODIFIED Fri Jun 16 17:48:26 2017
J 0
(-1425 325);
DISPLAY 1.340426 (-1425 325);
PAINT GREEN (-1425 325);
DISPLAY INVISIBLE (-1425 325);
FORCEPROP 1 LAST CUSTOM_TXT_CDS <CURRENT_DESIGN_SHEET> OF <TOTAL_DESIGN_SHEETS>
J 0
(-500 25);
PAINT ORANGE (-500 25);
FORCEPROP 1 LAST CUSTOM_TXT_CDS <CON_LAST_MODIFIED>
J 0
(-4000 100);
PAINT ORANGE (-4000 100);
FORCEPROP 2 LAST CUSTOM_TXT_CDS <XR_PAGE_TITLE>
J 0
(-7890 5250);
DISPLAY 0.638298 (-7890 5250);
PAINT PINK (-7890 5250);
DISPLAY INVISIBLE (-7890 5250);
FORCEPROP 1 LAST SCH_TITLE SKYLAKE - SKT1 - 19 OF 21
J 0
(-7950 50);
DISPLAY 1.212766 (-7950 50);
PAINT GREEN (-7950 50);
FORCEPROP 1 LAST COMMENT_BODY TRUE
J 0
(12 12);
DISPLAY 0.638298 (12 12);
PAINT GREEN (12 12);
DISPLAY INVISIBLE (12 12);
FORCEPROP 2 LAST CDS_LIB mstr_symbols
J 0
(0 0);
PAINT ORANGE (0 0);
DISPLAY INVISIBLE (0 0);
FORCEPROP 2 LAST PAGE_BORDER TRUE
J 0
(-7890 5250);
DISPLAY 0.851064 (-7890 5250);
PAINT PINK (-7890 5250);
DISPLAY INVISIBLE (-7890 5250);
FORCEPROP 2 LAST CDS_XR_PAGE_TITLE CR-73 : @BASEBOARD_FAB2_LIB.BASEBOARD_FAB2(SCH_1):PAGE73
J 0
(-7890 5250);
DISPLAY 0.638298 (-7890 5250);
PAINT PINK (-7890 5250);
DISPLAY INVISIBLE (-7890 5250);
FORCEADD DESIGN_NOTE..1
(-4825 575);
FORCEPROP 0 LAST L1 CPU SYMBOLS 1-30 ARE PRELIMINARY AND SUBJECT TO CHANGE
J 0
(-5025 450);
DISPLAY 1.021277 (-5025 450);
PAINT ORANGE (-5025 450);
FORCEPROP 1 LAST COMMENT_BODY TRUE
J 0
(-4800 675);
DISPLAY 0.978723 (-4800 675);
PAINT ORANGE (-4800 675);
DISPLAY INVISIBLE (-4800 675);
FORCEPROP 2 LAST CDS_LIB mstr_symbols
J 0
(-4825 575);
PAINT ORANGE (-4825 575);
DISPLAY INVISIBLE (-4825 575);
WIRE 16 -1 (-1800 4050)(-1800 3850);
WIRE 16 -1 (-1800 3550)(-1800 3850);
WIRE 16 -1 (-2950 3850)(-1800 3850);
WIRE 16 -1 (-2950 3550)(-1800 3550);
WIRE 16 -1 (-6600 1925)(-6600 1850);
WIRE 16 -1 (-6600 1850)(-5225 1850);
WIRE 16 -1 (-5225 1700)(-5225 1850);
WIRE 16 -1 (-5225 1850)(-5050 1850);
WIRE 16 -1 (-5225 1550)(-5225 1700);
WIRE 16 -1 (-5225 1700)(-5050 1700);
WIRE 16 -1 (-5225 1400)(-5225 1550);
WIRE 16 -1 (-5225 1550)(-5050 1550);
WIRE 16 -1 (-5225 1400)(-5225 1250);
WIRE 16 -1 (-5225 1400)(-5050 1400);
WIRE 16 -1 (-5225 1250)(-5050 1250);
WIRE 16 -1 (-5925 2800)(-5925 2900);
WIRE 16 -1 (-5250 2800)(-5925 2800);
WIRE 16 -1 (-5250 2750)(-5250 2800);
WIRE 16 -1 (-5050 2800)(-5250 2800);
WIRE 16 -1 (-5250 2700)(-5250 2750);
WIRE 16 -1 (-5050 2750)(-5250 2750);
WIRE 16 -1 (-5250 2600)(-5250 2700);
WIRE 16 -1 (-5050 2700)(-5250 2700);
WIRE 16 -1 (-5050 2600)(-5250 2600);
WIRE 16 -1 (-5350 3950)(-5350 4375);
WIRE 16 -1 (-5350 3900)(-5350 3950);
WIRE 16 -1 (-5050 3950)(-5350 3950);
WIRE 16 -1 (-5350 3800)(-5350 3900);
WIRE 16 -1 (-5050 3900)(-5350 3900);
WIRE 16 -1 (-5350 3750)(-5350 3800);
WIRE 16 -1 (-5050 3800)(-5350 3800);
WIRE 16 -1 (-5350 3700)(-5350 3750);
WIRE 16 -1 (-5050 3750)(-5350 3750);
WIRE 16 -1 (-5350 3650)(-5350 3700);
WIRE 16 -1 (-5050 3700)(-5350 3700);
WIRE 16 -1 (-5350 3600)(-5350 3650);
WIRE 16 -1 (-5050 3650)(-5350 3650);
WIRE 16 -1 (-5350 3550)(-5350 3600);
WIRE 16 -1 (-5050 3600)(-5350 3600);
WIRE 16 -1 (-5350 3500)(-5350 3550);
WIRE 16 -1 (-5050 3550)(-5350 3550);
WIRE 16 -1 (-5350 3450)(-5350 3500);
WIRE 16 -1 (-5050 3500)(-5350 3500);
WIRE 16 -1 (-5350 3350)(-5350 3450);
WIRE 16 -1 (-5050 3450)(-5350 3450);
WIRE 16 -1 (-5350 3300)(-5350 3350);
WIRE 16 -1 (-5050 3350)(-5350 3350);
WIRE 16 -1 (-5350 3250)(-5350 3300);
WIRE 16 -1 (-5050 3300)(-5350 3300);
WIRE 16 -1 (-5350 3200)(-5350 3250);
WIRE 16 -1 (-5050 3250)(-5350 3250);
WIRE 16 -1 (-5350 3150)(-5350 3200);
WIRE 16 -1 (-5050 3200)(-5350 3200);
WIRE 16 -1 (-5350 3150)(-5350 3100);
WIRE 16 -1 (-5050 3150)(-5350 3150);
WIRE 16 -1 (-5350 3100)(-5350 3050);
WIRE 16 -1 (-5050 3100)(-5350 3100);
WIRE 16 -1 (-5350 3050)(-5350 3000);
WIRE 16 -1 (-5050 3050)(-5350 3050);
WIRE 16 -1 (-5350 3000)(-5350 2950);
WIRE 16 -1 (-5050 3000)(-5350 3000);
WIRE 16 -1 (-5350 2950)(-5350 2900);
WIRE 16 -1 (-5050 2950)(-5350 2950);
WIRE 16 -1 (-5050 2900)(-5350 2900);
WIRE 16 -1 (-5050 2650)(-5900 2650);
FORCEPROP 0 LAST SIG_NAME TP_CPU1_KTI2_AMONV
J 0
(-5835 2660);
DISPLAY 0.617021 (-5835 2660);
PAINT ORANGE (-5835 2660);
FORCEPROP 2 LASTPROP $XRERR UNIQUE?
J 0
(-6140 2650);
DISPLAY 0.638298 (-6140 2650);
PAINT MONO (-6140 2650);
DISPLAY INVISIBLE (-6140 2650);
WIRE 16 -1 (-5050 2350)(-6075 2350);
FORCEPROP 2 LAST SIG_NAME VSENSE_PVCCMCP_CPU1_SKT_VSEN
J 0
(-6060 2360);
DISPLAY 0.617021 (-6060 2360);
PAINT ORANGE (-6060 2360);
WIRE 16 -1 (-5050 2450)(-6075 2450);
FORCEPROP 2 LAST SIG_NAME VSENSE_PVSA_CPU1_SKT_VRTN
J 0
(-6060 2460);
DISPLAY 0.617021 (-6060 2460);
PAINT ORANGE (-6060 2460);
WIRE 16 -1 (-5050 2500)(-6075 2500);
FORCEPROP 2 LAST SIG_NAME VSENSE_PVSA_CPU1_SKT_VSEN
J 0
(-6060 2510);
DISPLAY 0.617021 (-6060 2510);
PAINT ORANGE (-6060 2510);
WIRE 16 -1 (-5050 2300)(-6075 2300);
FORCEPROP 2 LAST SIG_NAME VSENSE_PVCCMCP_CPU1_SKT_VRTN
J 0
(-6060 2310);
DISPLAY 0.617021 (-6060 2310);
PAINT ORANGE (-6060 2310);
WIRE 16 -1 (-2950 3100)(-2350 3100);
FORCEPROP 2 LAST SIG_NAME TP_CPU1_RSVD_43
J 0
(-2725 3098);
DISPLAY 0.617021 (-2725 3098);
PAINT ORANGE (-2725 3098);
FORCEPROP 2 LASTPROP $XRERR UNIQUE?
J 0
(-2320 3100);
DISPLAY 0.638298 (-2320 3100);
PAINT MONO (-2320 3100);
DISPLAY INVISIBLE (-2320 3100);
WIRE 16 -1 (-5050 1200)(-5775 1200);
FORCEPROP 0 LAST SIG_NAME TP_CPU1_RSVD_61
J 0
(-5785 1210);
DISPLAY 0.617021 (-5785 1210);
PAINT ORANGE (-5785 1210);
FORCEPROP 2 LASTPROP $XRERR UNIQUE?
J 0
(-6015 1200);
DISPLAY 0.638298 (-6015 1200);
PAINT MONO (-6015 1200);
DISPLAY INVISIBLE (-6015 1200);
WIRE 16 -1 (-5050 1300)(-5775 1300);
FORCEPROP 0 LAST SIG_NAME TP_CPU1_KTI2_DFX_DN
J 0
(-5773 1318);
DISPLAY 0.617021 (-5773 1318);
PAINT ORANGE (-5773 1318);
FORCEPROP 2 LASTPROP $XRERR UNIQUE?
J 0
(-6015 1300);
DISPLAY 0.638298 (-6015 1300);
PAINT MONO (-6015 1300);
DISPLAY INVISIBLE (-6015 1300);
WIRE 16 -1 (-5050 1350)(-5775 1350);
FORCEPROP 0 LAST SIG_NAME TP_CPU1_RSVD_64
J 0
(-5760 1360);
DISPLAY 0.617021 (-5760 1360);
PAINT ORANGE (-5760 1360);
FORCEPROP 2 LASTPROP $XRERR UNIQUE?
J 0
(-6015 1350);
DISPLAY 0.638298 (-6015 1350);
PAINT MONO (-6015 1350);
DISPLAY INVISIBLE (-6015 1350);
WIRE 16 -1 (-5050 1450)(-5775 1450);
FORCEPROP 0 LAST SIG_NAME TP_CPU1_RSVD_66
J 0
(-5785 1460);
DISPLAY 0.617021 (-5785 1460);
PAINT ORANGE (-5785 1460);
FORCEPROP 2 LASTPROP $XRERR UNIQUE?
J 0
(-6015 1450);
DISPLAY 0.638298 (-6015 1450);
PAINT MONO (-6015 1450);
DISPLAY INVISIBLE (-6015 1450);
WIRE 16 -1 (-5050 1500)(-5775 1500);
FORCEPROP 0 LAST SIG_NAME TP_CPU1_RSVD_67
J 0
(-5785 1510);
DISPLAY 0.617021 (-5785 1510);
PAINT ORANGE (-5785 1510);
FORCEPROP 2 LASTPROP $XRERR UNIQUE?
J 0
(-6015 1500);
DISPLAY 0.638298 (-6015 1500);
PAINT MONO (-6015 1500);
DISPLAY INVISIBLE (-6015 1500);
WIRE 16 -1 (-5050 1600)(-5775 1600);
FORCEPROP 0 LAST SIG_NAME TP_CPU1_RSVD_69
J 0
(-5760 1610);
DISPLAY 0.617021 (-5760 1610);
PAINT ORANGE (-5760 1610);
FORCEPROP 2 LASTPROP $XRERR UNIQUE?
J 0
(-6015 1600);
DISPLAY 0.638298 (-6015 1600);
PAINT MONO (-6015 1600);
DISPLAY INVISIBLE (-6015 1600);
WIRE 16 -1 (-5050 1650)(-5775 1650);
FORCEPROP 0 LAST SIG_NAME TP_CPU1_RSVD_70
J 0
(-5760 1660);
DISPLAY 0.617021 (-5760 1660);
PAINT ORANGE (-5760 1660);
FORCEPROP 2 LASTPROP $XRERR UNIQUE?
J 0
(-6015 1650);
DISPLAY 0.638298 (-6015 1650);
PAINT MONO (-6015 1650);
DISPLAY INVISIBLE (-6015 1650);
WIRE 16 -1 (-5050 1750)(-5775 1750);
FORCEPROP 0 LAST SIG_NAME TP_CPU1_RSVD_72
J 0
(-5760 1760);
DISPLAY 0.617021 (-5760 1760);
PAINT ORANGE (-5760 1760);
FORCEPROP 2 LASTPROP $XRERR UNIQUE?
J 0
(-6015 1750);
DISPLAY 0.638298 (-6015 1750);
PAINT MONO (-6015 1750);
DISPLAY INVISIBLE (-6015 1750);
WIRE 16 -1 (-5050 1800)(-5775 1800);
FORCEPROP 0 LAST SIG_NAME TP_CPU1_RSVD_73
J 0
(-5760 1810);
DISPLAY 0.617021 (-5760 1810);
PAINT ORANGE (-5760 1810);
FORCEPROP 2 LASTPROP $XRERR UNIQUE?
J 0
(-6015 1800);
DISPLAY 0.638298 (-6015 1800);
PAINT MONO (-6015 1800);
DISPLAY INVISIBLE (-6015 1800);
WIRE 16 -1 (-5050 1900)(-6075 1900);
FORCEPROP 0 LAST SIG_NAME PD_CPU1_MCP01_DMON
J 0
(-6035 1910);
DISPLAY 0.617021 (-6035 1910);
PAINT ORANGE (-6035 1910);
WIRE 16 -1 (-5050 2000)(-6075 2000);
FORCEPROP 2 LAST SIG_NAME VSENSE_PVCCIO_CPU1_SKT_VRTN
J 0
(-6060 2010);
DISPLAY 0.617021 (-6060 2010);
PAINT ORANGE (-6060 2010);
WIRE 16 -1 (-5050 2200)(-6075 2200);
FORCEPROP 2 LAST SIG_NAME VSENSE_PVCCIOMCP_CPU1_SKT_VSEN
J 0
(-6060 2210);
DISPLAY 0.617021 (-6060 2210);
PAINT ORANGE (-6060 2210);
WIRE 16 -1 (-5050 2150)(-6075 2150);
FORCEPROP 2 LAST SIG_NAME VSENSE_PVCCIOMCP_CPU1_SKT_VRTN
J 0
(-6060 2160);
DISPLAY 0.617021 (-6060 2160);
PAINT ORANGE (-6060 2160);
WIRE 16 -1 (-5050 2050)(-6075 2050);
FORCEPROP 2 LAST SIG_NAME VSENSE_PVCCIO_CPU1_SKT_VSEN
J 0
(-6060 2060);
DISPLAY 0.617021 (-6060 2060);
PAINT ORANGE (-6060 2060);
WIRE 16 -1 (-2950 950)(-2350 950);
FORCEPROP 2 LAST SIG_NAME TP_CPU1_RSVD_0
J 0
(-2725 948);
DISPLAY 0.617021 (-2725 948);
PAINT ORANGE (-2725 948);
FORCEPROP 2 LASTPROP $XRERR UNIQUE?
J 0
(-2320 950);
DISPLAY 0.638298 (-2320 950);
PAINT MONO (-2320 950);
DISPLAY INVISIBLE (-2320 950);
WIRE 16 -1 (-2950 1000)(-2350 1000);
FORCEPROP 2 LAST SIG_NAME TP_CPU1_RSVD_1
J 0
(-2725 998);
DISPLAY 0.617021 (-2725 998);
PAINT ORANGE (-2725 998);
FORCEPROP 2 LASTPROP $XRERR UNIQUE?
J 0
(-2320 1000);
DISPLAY 0.638298 (-2320 1000);
PAINT MONO (-2320 1000);
DISPLAY INVISIBLE (-2320 1000);
WIRE 16 -1 (-2950 1050)(-2350 1050);
FORCEPROP 2 LAST SIG_NAME TP_CPU1_RSVD_2
J 0
(-2725 1048);
DISPLAY 0.617021 (-2725 1048);
PAINT ORANGE (-2725 1048);
FORCEPROP 2 LASTPROP $XRERR UNIQUE?
J 0
(-2320 1050);
DISPLAY 0.638298 (-2320 1050);
PAINT MONO (-2320 1050);
DISPLAY INVISIBLE (-2320 1050);
WIRE 16 -1 (-2950 1100)(-2350 1100);
FORCEPROP 2 LAST SIG_NAME TP_CPU1_RSVD_3
J 0
(-2725 1098);
DISPLAY 0.617021 (-2725 1098);
PAINT ORANGE (-2725 1098);
FORCEPROP 2 LASTPROP $XRERR UNIQUE?
J 0
(-2320 1100);
DISPLAY 0.638298 (-2320 1100);
PAINT MONO (-2320 1100);
DISPLAY INVISIBLE (-2320 1100);
WIRE 16 -1 (-2950 1150)(-2350 1150);
FORCEPROP 2 LAST SIG_NAME TP_CPU1_RSVD_4
J 0
(-2725 1148);
DISPLAY 0.617021 (-2725 1148);
PAINT ORANGE (-2725 1148);
FORCEPROP 2 LASTPROP $XRERR UNIQUE?
J 0
(-2320 1150);
DISPLAY 0.638298 (-2320 1150);
PAINT MONO (-2320 1150);
DISPLAY INVISIBLE (-2320 1150);
WIRE 16 -1 (-2950 1200)(-2350 1200);
FORCEPROP 2 LAST SIG_NAME TP_CPU1_RSVD_5
J 0
(-2725 1198);
DISPLAY 0.617021 (-2725 1198);
PAINT ORANGE (-2725 1198);
FORCEPROP 2 LASTPROP $XRERR UNIQUE?
J 0
(-2320 1200);
DISPLAY 0.638298 (-2320 1200);
PAINT MONO (-2320 1200);
DISPLAY INVISIBLE (-2320 1200);
WIRE 16 -1 (-2950 1250)(-2350 1250);
FORCEPROP 2 LAST SIG_NAME TP_CPU1_RSVD_6
J 0
(-2725 1248);
DISPLAY 0.617021 (-2725 1248);
PAINT ORANGE (-2725 1248);
FORCEPROP 2 LASTPROP $XRERR UNIQUE?
J 0
(-2320 1250);
DISPLAY 0.638298 (-2320 1250);
PAINT MONO (-2320 1250);
DISPLAY INVISIBLE (-2320 1250);
WIRE 16 -1 (-2950 1300)(-2350 1300);
FORCEPROP 2 LAST SIG_NAME TP_CPU1_RSVD_7
J 0
(-2725 1298);
DISPLAY 0.617021 (-2725 1298);
PAINT ORANGE (-2725 1298);
FORCEPROP 2 LASTPROP $XRERR UNIQUE?
J 0
(-2320 1300);
DISPLAY 0.638298 (-2320 1300);
PAINT MONO (-2320 1300);
DISPLAY INVISIBLE (-2320 1300);
WIRE 16 -1 (-2950 1350)(-2350 1350);
FORCEPROP 2 LAST SIG_NAME TP_CPU1_RSVD_8
J 0
(-2725 1348);
DISPLAY 0.617021 (-2725 1348);
PAINT ORANGE (-2725 1348);
FORCEPROP 2 LASTPROP $XRERR UNIQUE?
J 0
(-2320 1350);
DISPLAY 0.638298 (-2320 1350);
PAINT MONO (-2320 1350);
DISPLAY INVISIBLE (-2320 1350);
WIRE 16 -1 (-2950 1400)(-2350 1400);
FORCEPROP 2 LAST SIG_NAME TP_CPU1_RSVD_9
J 0
(-2725 1398);
DISPLAY 0.617021 (-2725 1398);
PAINT ORANGE (-2725 1398);
FORCEPROP 2 LASTPROP $XRERR UNIQUE?
J 0
(-2320 1400);
DISPLAY 0.638298 (-2320 1400);
PAINT MONO (-2320 1400);
DISPLAY INVISIBLE (-2320 1400);
WIRE 16 -1 (-2950 1450)(-2350 1450);
FORCEPROP 2 LAST SIG_NAME TP_CPU1_RSVD_10
J 0
(-2725 1448);
DISPLAY 0.617021 (-2725 1448);
PAINT ORANGE (-2725 1448);
FORCEPROP 2 LASTPROP $XRERR UNIQUE?
J 0
(-2320 1450);
DISPLAY 0.638298 (-2320 1450);
PAINT MONO (-2320 1450);
DISPLAY INVISIBLE (-2320 1450);
WIRE 16 -1 (-2950 1500)(-2350 1500);
FORCEPROP 2 LAST SIG_NAME TP_CPU1_RSVD_11
J 0
(-2725 1498);
DISPLAY 0.617021 (-2725 1498);
PAINT ORANGE (-2725 1498);
FORCEPROP 2 LASTPROP $XRERR UNIQUE?
J 0
(-2320 1500);
DISPLAY 0.638298 (-2320 1500);
PAINT MONO (-2320 1500);
DISPLAY INVISIBLE (-2320 1500);
WIRE 16 -1 (-2950 1550)(-2350 1550);
FORCEPROP 2 LAST SIG_NAME TP_CPU1_RSVD_12
J 0
(-2725 1548);
DISPLAY 0.617021 (-2725 1548);
PAINT ORANGE (-2725 1548);
FORCEPROP 2 LASTPROP $XRERR UNIQUE?
J 0
(-2320 1550);
DISPLAY 0.638298 (-2320 1550);
PAINT MONO (-2320 1550);
DISPLAY INVISIBLE (-2320 1550);
WIRE 16 -1 (-2950 1600)(-2350 1600);
FORCEPROP 2 LAST SIG_NAME TP_CPU1_RSVD_13
J 0
(-2725 1598);
DISPLAY 0.617021 (-2725 1598);
PAINT ORANGE (-2725 1598);
FORCEPROP 2 LASTPROP $XRERR UNIQUE?
J 0
(-2320 1600);
DISPLAY 0.638298 (-2320 1600);
PAINT MONO (-2320 1600);
DISPLAY INVISIBLE (-2320 1600);
WIRE 16 -1 (-2950 1650)(-2350 1650);
FORCEPROP 2 LAST SIG_NAME TP_CPU1_RSVD_14
J 0
(-2725 1648);
DISPLAY 0.617021 (-2725 1648);
PAINT ORANGE (-2725 1648);
FORCEPROP 2 LASTPROP $XRERR UNIQUE?
J 0
(-2320 1650);
DISPLAY 0.638298 (-2320 1650);
PAINT MONO (-2320 1650);
DISPLAY INVISIBLE (-2320 1650);
WIRE 16 -1 (-2950 1700)(-2350 1700);
FORCEPROP 2 LAST SIG_NAME TP_CPU1_RSVD_15
J 0
(-2725 1698);
DISPLAY 0.617021 (-2725 1698);
PAINT ORANGE (-2725 1698);
FORCEPROP 2 LASTPROP $XRERR UNIQUE?
J 0
(-2320 1700);
DISPLAY 0.638298 (-2320 1700);
PAINT MONO (-2320 1700);
DISPLAY INVISIBLE (-2320 1700);
WIRE 16 -1 (-2950 1750)(-2350 1750);
FORCEPROP 2 LAST SIG_NAME TP_CPU1_RSVD_16
J 0
(-2725 1748);
DISPLAY 0.617021 (-2725 1748);
PAINT ORANGE (-2725 1748);
FORCEPROP 2 LASTPROP $XRERR UNIQUE?
J 0
(-2320 1750);
DISPLAY 0.638298 (-2320 1750);
PAINT MONO (-2320 1750);
DISPLAY INVISIBLE (-2320 1750);
WIRE 16 -1 (-2950 1800)(-2350 1800);
FORCEPROP 2 LAST SIG_NAME TP_CPU1_RSVD_17
J 0
(-2725 1798);
DISPLAY 0.617021 (-2725 1798);
PAINT ORANGE (-2725 1798);
FORCEPROP 2 LASTPROP $XRERR UNIQUE?
J 0
(-2320 1800);
DISPLAY 0.638298 (-2320 1800);
PAINT MONO (-2320 1800);
DISPLAY INVISIBLE (-2320 1800);
WIRE 16 -1 (-2950 1850)(-2350 1850);
FORCEPROP 2 LAST SIG_NAME TP_CPU1_RSVD_18
J 0
(-2725 1848);
DISPLAY 0.617021 (-2725 1848);
PAINT ORANGE (-2725 1848);
FORCEPROP 2 LASTPROP $XRERR UNIQUE?
J 0
(-2320 1850);
DISPLAY 0.638298 (-2320 1850);
PAINT MONO (-2320 1850);
DISPLAY INVISIBLE (-2320 1850);
WIRE 16 -1 (-2950 1900)(-2350 1900);
FORCEPROP 2 LAST SIG_NAME TP_CPU1_RSVD_19
J 0
(-2725 1898);
DISPLAY 0.617021 (-2725 1898);
PAINT ORANGE (-2725 1898);
FORCEPROP 2 LASTPROP $XRERR UNIQUE?
J 0
(-2320 1900);
DISPLAY 0.638298 (-2320 1900);
PAINT MONO (-2320 1900);
DISPLAY INVISIBLE (-2320 1900);
WIRE 16 -1 (-2950 1950)(-2350 1950);
FORCEPROP 2 LAST SIG_NAME TP_CPU1_RSVD_20
J 0
(-2725 1948);
DISPLAY 0.617021 (-2725 1948);
PAINT ORANGE (-2725 1948);
FORCEPROP 2 LASTPROP $XRERR UNIQUE?
J 0
(-2320 1950);
DISPLAY 0.638298 (-2320 1950);
PAINT MONO (-2320 1950);
DISPLAY INVISIBLE (-2320 1950);
WIRE 16 -1 (-2950 2000)(-2350 2000);
FORCEPROP 2 LAST SIG_NAME TP_CPU1_RSVD_21
J 0
(-2725 1998);
DISPLAY 0.617021 (-2725 1998);
PAINT ORANGE (-2725 1998);
FORCEPROP 2 LASTPROP $XRERR UNIQUE?
J 0
(-2320 2000);
DISPLAY 0.638298 (-2320 2000);
PAINT MONO (-2320 2000);
DISPLAY INVISIBLE (-2320 2000);
WIRE 16 -1 (-2950 2050)(-2350 2050);
FORCEPROP 2 LAST SIG_NAME TP_CPU1_RSVD_22
J 0
(-2725 2048);
DISPLAY 0.617021 (-2725 2048);
PAINT ORANGE (-2725 2048);
FORCEPROP 2 LASTPROP $XRERR UNIQUE?
J 0
(-2320 2050);
DISPLAY 0.638298 (-2320 2050);
PAINT MONO (-2320 2050);
DISPLAY INVISIBLE (-2320 2050);
WIRE 16 -1 (-2950 2100)(-2350 2100);
FORCEPROP 2 LAST SIG_NAME TP_CPU1_RSVD_23
J 0
(-2725 2098);
DISPLAY 0.617021 (-2725 2098);
PAINT ORANGE (-2725 2098);
FORCEPROP 2 LASTPROP $XRERR UNIQUE?
J 0
(-2320 2100);
DISPLAY 0.638298 (-2320 2100);
PAINT MONO (-2320 2100);
DISPLAY INVISIBLE (-2320 2100);
WIRE 16 -1 (-2950 2150)(-2350 2150);
FORCEPROP 2 LAST SIG_NAME TP_CPU1_RSVD_24
J 0
(-2725 2148);
DISPLAY 0.617021 (-2725 2148);
PAINT ORANGE (-2725 2148);
FORCEPROP 2 LASTPROP $XRERR UNIQUE?
J 0
(-2320 2150);
DISPLAY 0.638298 (-2320 2150);
PAINT MONO (-2320 2150);
DISPLAY INVISIBLE (-2320 2150);
WIRE 16 -1 (-2950 2200)(-2350 2200);
FORCEPROP 2 LAST SIG_NAME TP_CPU1_RSVD_25
J 0
(-2725 2198);
DISPLAY 0.617021 (-2725 2198);
PAINT ORANGE (-2725 2198);
FORCEPROP 2 LASTPROP $XRERR UNIQUE?
J 0
(-2320 2200);
DISPLAY 0.638298 (-2320 2200);
PAINT MONO (-2320 2200);
DISPLAY INVISIBLE (-2320 2200);
WIRE 16 -1 (-2950 2250)(-2350 2250);
FORCEPROP 2 LAST SIG_NAME TP_CPU1_RSVD_26
J 0
(-2725 2248);
DISPLAY 0.617021 (-2725 2248);
PAINT ORANGE (-2725 2248);
FORCEPROP 2 LASTPROP $XRERR UNIQUE?
J 0
(-2320 2250);
DISPLAY 0.638298 (-2320 2250);
PAINT MONO (-2320 2250);
DISPLAY INVISIBLE (-2320 2250);
WIRE 16 -1 (-2950 2300)(-2350 2300);
FORCEPROP 2 LAST SIG_NAME TP_CPU1_RSVD_27
J 0
(-2725 2298);
DISPLAY 0.617021 (-2725 2298);
PAINT ORANGE (-2725 2298);
FORCEPROP 2 LASTPROP $XRERR UNIQUE?
J 0
(-2320 2300);
DISPLAY 0.638298 (-2320 2300);
PAINT MONO (-2320 2300);
DISPLAY INVISIBLE (-2320 2300);
WIRE 16 -1 (-2950 2350)(-2350 2350);
FORCEPROP 2 LAST SIG_NAME TP_CPU1_RSVD_28
J 0
(-2725 2348);
DISPLAY 0.617021 (-2725 2348);
PAINT ORANGE (-2725 2348);
FORCEPROP 2 LASTPROP $XRERR UNIQUE?
J 0
(-2320 2350);
DISPLAY 0.638298 (-2320 2350);
PAINT MONO (-2320 2350);
DISPLAY INVISIBLE (-2320 2350);
WIRE 16 -1 (-2950 2400)(-2350 2400);
FORCEPROP 2 LAST SIG_NAME TP_CPU1_RSVD_29
J 0
(-2725 2398);
DISPLAY 0.617021 (-2725 2398);
PAINT ORANGE (-2725 2398);
FORCEPROP 2 LASTPROP $XRERR UNIQUE?
J 0
(-2320 2400);
DISPLAY 0.638298 (-2320 2400);
PAINT MONO (-2320 2400);
DISPLAY INVISIBLE (-2320 2400);
WIRE 16 -1 (-2950 2450)(-2350 2450);
FORCEPROP 2 LAST SIG_NAME TP_CPU1_RSVD_30
J 0
(-2725 2448);
DISPLAY 0.617021 (-2725 2448);
PAINT ORANGE (-2725 2448);
FORCEPROP 2 LASTPROP $XRERR UNIQUE?
J 0
(-2320 2450);
DISPLAY 0.638298 (-2320 2450);
PAINT MONO (-2320 2450);
DISPLAY INVISIBLE (-2320 2450);
WIRE 16 -1 (-2950 2500)(-2350 2500);
FORCEPROP 2 LAST SIG_NAME TP_CPU1_RSVD_31
J 0
(-2725 2498);
DISPLAY 0.617021 (-2725 2498);
PAINT ORANGE (-2725 2498);
FORCEPROP 2 LASTPROP $XRERR UNIQUE?
J 0
(-2320 2500);
DISPLAY 0.638298 (-2320 2500);
PAINT MONO (-2320 2500);
DISPLAY INVISIBLE (-2320 2500);
WIRE 16 -1 (-2950 2550)(-2350 2550);
FORCEPROP 2 LAST SIG_NAME TP_CPU1_RSVD_32
J 0
(-2725 2548);
DISPLAY 0.617021 (-2725 2548);
PAINT ORANGE (-2725 2548);
FORCEPROP 2 LASTPROP $XRERR UNIQUE?
J 0
(-2320 2550);
DISPLAY 0.638298 (-2320 2550);
PAINT MONO (-2320 2550);
DISPLAY INVISIBLE (-2320 2550);
WIRE 16 -1 (-2950 2600)(-2350 2600);
FORCEPROP 2 LAST SIG_NAME TP_CPU1_RSVD_33
J 0
(-2725 2598);
DISPLAY 0.617021 (-2725 2598);
PAINT ORANGE (-2725 2598);
FORCEPROP 2 LASTPROP $XRERR UNIQUE?
J 0
(-2320 2600);
DISPLAY 0.638298 (-2320 2600);
PAINT MONO (-2320 2600);
DISPLAY INVISIBLE (-2320 2600);
WIRE 16 -1 (-2950 2650)(-2350 2650);
FORCEPROP 2 LAST SIG_NAME TP_CPU1_RSVD_34
J 0
(-2725 2648);
DISPLAY 0.617021 (-2725 2648);
PAINT ORANGE (-2725 2648);
FORCEPROP 2 LASTPROP $XRERR UNIQUE?
J 0
(-2320 2650);
DISPLAY 0.638298 (-2320 2650);
PAINT MONO (-2320 2650);
DISPLAY INVISIBLE (-2320 2650);
WIRE 16 -1 (-2950 2700)(-2350 2700);
FORCEPROP 2 LAST SIG_NAME TP_CPU1_RSVD_35
J 0
(-2725 2698);
DISPLAY 0.617021 (-2725 2698);
PAINT ORANGE (-2725 2698);
FORCEPROP 2 LASTPROP $XRERR UNIQUE?
J 0
(-2320 2700);
DISPLAY 0.638298 (-2320 2700);
PAINT MONO (-2320 2700);
DISPLAY INVISIBLE (-2320 2700);
WIRE 16 -1 (-2950 2750)(-2350 2750);
FORCEPROP 2 LAST SIG_NAME TP_CPU1_RSVD_36
J 0
(-2725 2748);
DISPLAY 0.617021 (-2725 2748);
PAINT ORANGE (-2725 2748);
FORCEPROP 2 LASTPROP $XRERR UNIQUE?
J 0
(-2320 2750);
DISPLAY 0.638298 (-2320 2750);
PAINT MONO (-2320 2750);
DISPLAY INVISIBLE (-2320 2750);
WIRE 16 -1 (-2950 2800)(-2350 2800);
FORCEPROP 2 LAST SIG_NAME TP_CPU1_RSVD_37
J 0
(-2725 2798);
DISPLAY 0.617021 (-2725 2798);
PAINT ORANGE (-2725 2798);
FORCEPROP 2 LASTPROP $XRERR UNIQUE?
J 0
(-2320 2800);
DISPLAY 0.638298 (-2320 2800);
PAINT MONO (-2320 2800);
DISPLAY INVISIBLE (-2320 2800);
WIRE 16 -1 (-2950 2850)(-2350 2850);
FORCEPROP 2 LAST SIG_NAME TP_CPU1_RSVD_38
J 0
(-2725 2848);
DISPLAY 0.617021 (-2725 2848);
PAINT ORANGE (-2725 2848);
FORCEPROP 2 LASTPROP $XRERR UNIQUE?
J 0
(-2320 2850);
DISPLAY 0.638298 (-2320 2850);
PAINT MONO (-2320 2850);
DISPLAY INVISIBLE (-2320 2850);
WIRE 16 -1 (-2950 2900)(-2350 2900);
FORCEPROP 2 LAST SIG_NAME TP_CPU1_RSVD_39
J 0
(-2725 2898);
DISPLAY 0.617021 (-2725 2898);
PAINT ORANGE (-2725 2898);
FORCEPROP 2 LASTPROP $XRERR UNIQUE?
J 0
(-2320 2900);
DISPLAY 0.638298 (-2320 2900);
PAINT MONO (-2320 2900);
DISPLAY INVISIBLE (-2320 2900);
WIRE 16 -1 (-2950 2950)(-2350 2950);
FORCEPROP 2 LAST SIG_NAME TP_CPU1_RSVD_40
J 0
(-2725 2948);
DISPLAY 0.617021 (-2725 2948);
PAINT ORANGE (-2725 2948);
FORCEPROP 2 LASTPROP $XRERR UNIQUE?
J 0
(-2320 2950);
DISPLAY 0.638298 (-2320 2950);
PAINT MONO (-2320 2950);
DISPLAY INVISIBLE (-2320 2950);
WIRE 16 -1 (-2950 3000)(-2350 3000);
FORCEPROP 2 LAST SIG_NAME TP_CPU1_RSVD_41
J 0
(-2725 2998);
DISPLAY 0.617021 (-2725 2998);
PAINT ORANGE (-2725 2998);
FORCEPROP 2 LASTPROP $XRERR UNIQUE?
J 0
(-2320 3000);
DISPLAY 0.638298 (-2320 3000);
PAINT MONO (-2320 3000);
DISPLAY INVISIBLE (-2320 3000);
WIRE 16 -1 (-2950 3050)(-2350 3050);
FORCEPROP 2 LAST SIG_NAME TP_CPU1_RSVD_42
J 0
(-2725 3048);
DISPLAY 0.617021 (-2725 3048);
PAINT ORANGE (-2725 3048);
FORCEPROP 2 LASTPROP $XRERR UNIQUE?
J 0
(-2320 3050);
DISPLAY 0.638298 (-2320 3050);
PAINT MONO (-2320 3050);
DISPLAY INVISIBLE (-2320 3050);
WIRE 16 -1 (-2950 3150)(-2350 3150);
FORCEPROP 2 LAST SIG_NAME TP_CPU1_RSVD_44
J 0
(-2725 3148);
DISPLAY 0.617021 (-2725 3148);
PAINT ORANGE (-2725 3148);
FORCEPROP 2 LASTPROP $XRERR UNIQUE?
J 0
(-2320 3150);
DISPLAY 0.638298 (-2320 3150);
PAINT MONO (-2320 3150);
DISPLAY INVISIBLE (-2320 3150);
WIRE 16 -1 (-2950 3200)(-2350 3200);
FORCEPROP 2 LAST SIG_NAME TP_CPU1_RSVD_45
J 0
(-2725 3198);
DISPLAY 0.617021 (-2725 3198);
PAINT ORANGE (-2725 3198);
FORCEPROP 2 LASTPROP $XRERR UNIQUE?
J 0
(-2320 3200);
DISPLAY 0.638298 (-2320 3200);
PAINT MONO (-2320 3200);
DISPLAY INVISIBLE (-2320 3200);
WIRE 16 -1 (-2950 3250)(-2350 3250);
FORCEPROP 2 LAST SIG_NAME TP_CPU1_RSVD_46
J 0
(-2725 3248);
DISPLAY 0.617021 (-2725 3248);
PAINT ORANGE (-2725 3248);
FORCEPROP 2 LASTPROP $XRERR UNIQUE?
J 0
(-2320 3250);
DISPLAY 0.638298 (-2320 3250);
PAINT MONO (-2320 3250);
DISPLAY INVISIBLE (-2320 3250);
WIRE 16 -1 (-2950 3300)(-2350 3300);
FORCEPROP 2 LAST SIG_NAME TP_CPU1_RSVD_47
J 0
(-2725 3298);
DISPLAY 0.617021 (-2725 3298);
PAINT ORANGE (-2725 3298);
FORCEPROP 2 LASTPROP $XRERR UNIQUE?
J 0
(-2320 3300);
DISPLAY 0.638298 (-2320 3300);
PAINT MONO (-2320 3300);
DISPLAY INVISIBLE (-2320 3300);
WIRE 16 -1 (-2950 3350)(-2350 3350);
FORCEPROP 2 LAST SIG_NAME TP_CPU1_RSVD_48
J 0
(-2725 3348);
DISPLAY 0.617021 (-2725 3348);
PAINT ORANGE (-2725 3348);
FORCEPROP 2 LASTPROP $XRERR UNIQUE?
J 0
(-2320 3350);
DISPLAY 0.638298 (-2320 3350);
PAINT MONO (-2320 3350);
DISPLAY INVISIBLE (-2320 3350);
WIRE 16 -1 (-2950 3400)(-2350 3400);
FORCEPROP 2 LAST SIG_NAME TP_CPU1_RSVD_49
J 0
(-2725 3398);
DISPLAY 0.617021 (-2725 3398);
PAINT ORANGE (-2725 3398);
FORCEPROP 2 LASTPROP $XRERR UNIQUE?
J 0
(-2320 3400);
DISPLAY 0.638298 (-2320 3400);
PAINT MONO (-2320 3400);
DISPLAY INVISIBLE (-2320 3400);
WIRE 16 -1 (-2950 3450)(-2350 3450);
FORCEPROP 2 LAST SIG_NAME TP_CPU1_RSVD_50
J 0
(-2725 3448);
DISPLAY 0.617021 (-2725 3448);
PAINT ORANGE (-2725 3448);
FORCEPROP 2 LASTPROP $XRERR UNIQUE?
J 0
(-2320 3450);
DISPLAY 0.638298 (-2320 3450);
PAINT MONO (-2320 3450);
DISPLAY INVISIBLE (-2320 3450);
WIRE 16 -1 (-2950 3500)(-2350 3500);
FORCEPROP 2 LAST SIG_NAME TP_CPU1_RSVD_51
J 0
(-2725 3498);
DISPLAY 0.617021 (-2725 3498);
PAINT ORANGE (-2725 3498);
FORCEPROP 2 LASTPROP $XRERR UNIQUE?
J 0
(-2320 3500);
DISPLAY 0.638298 (-2320 3500);
PAINT MONO (-2320 3500);
DISPLAY INVISIBLE (-2320 3500);
WIRE 16 -1 (-2950 3600)(-2350 3600);
FORCEPROP 2 LAST SIG_NAME TP_CPU1_RSVD_53
J 0
(-2725 3598);
DISPLAY 0.617021 (-2725 3598);
PAINT ORANGE (-2725 3598);
FORCEPROP 2 LASTPROP $XRERR UNIQUE?
J 0
(-2320 3600);
DISPLAY 0.638298 (-2320 3600);
PAINT MONO (-2320 3600);
DISPLAY INVISIBLE (-2320 3600);
WIRE 16 -1 (-2950 3650)(-2350 3650);
FORCEPROP 2 LAST SIG_NAME TP_CPU1_RSVD_54
J 0
(-2725 3648);
DISPLAY 0.617021 (-2725 3648);
PAINT ORANGE (-2725 3648);
FORCEPROP 2 LASTPROP $XRERR UNIQUE?
J 0
(-2320 3650);
DISPLAY 0.638298 (-2320 3650);
PAINT MONO (-2320 3650);
DISPLAY INVISIBLE (-2320 3650);
WIRE 16 -1 (-2950 3700)(-2350 3700);
FORCEPROP 2 LAST SIG_NAME TP_CPU1_RSVD_55
J 0
(-2725 3698);
DISPLAY 0.617021 (-2725 3698);
PAINT ORANGE (-2725 3698);
FORCEPROP 2 LASTPROP $XRERR UNIQUE?
J 0
(-2320 3700);
DISPLAY 0.638298 (-2320 3700);
PAINT MONO (-2320 3700);
DISPLAY INVISIBLE (-2320 3700);
WIRE 16 -1 (-2950 3750)(-2350 3750);
FORCEPROP 2 LAST SIG_NAME TP_CPU1_RSVD_56
J 0
(-2725 3748);
DISPLAY 0.617021 (-2725 3748);
PAINT ORANGE (-2725 3748);
FORCEPROP 2 LASTPROP $XRERR UNIQUE?
J 0
(-2320 3750);
DISPLAY 0.638298 (-2320 3750);
PAINT MONO (-2320 3750);
DISPLAY INVISIBLE (-2320 3750);
WIRE 16 -1 (-2950 3800)(-2350 3800);
FORCEPROP 2 LAST SIG_NAME TP_CPU1_RSVD_57
J 0
(-2725 3798);
DISPLAY 0.617021 (-2725 3798);
PAINT ORANGE (-2725 3798);
FORCEPROP 2 LASTPROP $XRERR UNIQUE?
J 0
(-2320 3800);
DISPLAY 0.638298 (-2320 3800);
PAINT MONO (-2320 3800);
DISPLAY INVISIBLE (-2320 3800);
WIRE 16 -1 (-2950 3900)(-2350 3900);
FORCEPROP 2 LAST SIG_NAME TP_CPU1_RSVD_59
J 0
(-2725 3898);
DISPLAY 0.617021 (-2725 3898);
PAINT ORANGE (-2725 3898);
FORCEPROP 2 LASTPROP $XRERR UNIQUE?
J 0
(-2320 3900);
DISPLAY 0.638298 (-2320 3900);
PAINT MONO (-2320 3900);
DISPLAY INVISIBLE (-2320 3900);
WIRE 16 -1 (-2950 3950)(-2350 3950);
FORCEPROP 2 LAST SIG_NAME TP_CPU1_RSVD_60
J 0
(-2725 3948);
DISPLAY 0.617021 (-2725 3948);
PAINT ORANGE (-2725 3948);
FORCEPROP 2 LASTPROP $XRERR UNIQUE?
J 0
(-2320 3950);
DISPLAY 0.638298 (-2320 3950);
PAINT MONO (-2320 3950);
DISPLAY INVISIBLE (-2320 3950);
DOT 1 (-5350 3750);
DOT 1 (-5350 3800);
DOT 1 (-5225 1700);
DOT 1 (-5250 2700);
DOT 1 (-5250 2750);
DOT 1 (-5350 3050);
DOT 1 (-5225 1850);
DOT 1 (-1800 3850);
DOT 1 (-5350 3600);
DOT 1 (-5225 1400);
DOT 1 (-5350 3500);
DOT 1 (-5350 3100);
DOT 1 (-5350 3000);
DOT 1 (-5350 2950);
DOT 1 (-5350 3300);
DOT 1 (-5350 3350);
DOT 1 (-5350 3450);
DOT 1 (-5350 3550);
DOT 1 (-5350 3650);
DOT 1 (-5350 3700);
DOT 1 (-5350 3900);
DOT 1 (-5350 3950);
DOT 1 (-5350 3150);
DOT 1 (-5350 3200);
DOT 1 (-5350 3250);
DOT 1 (-5225 1550);
DOT 1 (-5250 2800);
FORCENOTE
BOM_COST=PROC_SOCKET
(-7925 200) 0;
DISPLAY LEFT (-7925 200);
DISPLAY 1.723404 (-7925 200);
PAINT PURPLE (-7925 200);
FORCENOTE
ROOM=CPU1
(-7925 325) 0;
DISPLAY LEFT (-7925 325);
DISPLAY 1.723404 (-7925 325);
PAINT PURPLE (-7925 325);
QUIT
